(kicad_pcb
	(version 20260206)
	(generator "pcbnew")
	(generator_version "10.0")
	(general
		(thickness 1.21888)
		(legacy_teardrops no)
	)
	(paper "A4")
	(title_block
		(title "timecard-v9 — TimeCard-DC-V9_EXP.PcbDoc")
		(comment 1 "Time Appliance Project (Time Card) / footprints 378-388 of 402")
	)
	(layers
		(0 "F.Cu" signal "TOP")
		(4 "In1.Cu" signal "SGND")
		(6 "In2.Cu" signal "IN1")
		(8 "In3.Cu" signal "IN2")
		(10 "In4.Cu" signal "SGND1")
		(2 "B.Cu" signal "BOTTOM")
		(9 "F.Adhes" user "F.Adhesive")
		(11 "B.Adhes" user "B.Adhesive")
		(13 "F.Paste" user "Top Paste")
		(15 "B.Paste" user "Bottom Paste")
		(5 "F.SilkS" user "Top Overlay")
		(7 "B.SilkS" user "Bottom Overlay")
		(1 "F.Mask" user "Top Solder")
		(3 "B.Mask" user "Bottom Solder")
		(17 "Dwgs.User" user "User.Drawings")
		(19 "Cmts.User" user "User.Comments")
		(21 "Eco1.User" user "User.Eco1")
		(23 "Eco2.User" user "User.Eco2")
		(25 "Edge.Cuts" user)
		(27 "Margin" user)
		(31 "F.CrtYd" user "Top Courtyard")
		(29 "B.CrtYd" user "Bottom Courtyard")
		(35 "F.Fab" user "Top Component Center")
		(33 "B.Fab" user "Bottom Component Center")
	)
	(footprint "Vault:FP-0402-L_1_0_1-W_0_5_0_1-IPC_C"
		(layer "B.Cu")
		(at 194.1216 122.6162 180)
		(property "Reference" "C106"
			(at 0.6032 1.673069 0)
			(unlocked yes)
			(layer "B.SilkS")
			(effects
				(font
					(size 0.762 0.762)
					(thickness 0.2032)
				)
				(justify mirror)
			)
		)
		(property "Value" "0.1uF_25V_0402"
			(at -2.465551 -9.813815 90)
			(unlocked yes)
			(layer "B.SilkS")
			(hide yes)
			(effects
				(font
					(size 0.762 0.762)
					(thickness 0.2032)
				)
				(justify mirror)
			)
		)
		(sheetname "11-M2_RCB_MUX")
		(sheetfile "11-M2_RCB_MUX.kicad_sch")
		(duplicate_pad_numbers_are_jumpers no)
		(fp_line
			(start 0.65607 0.7)
			(end -0.65607 0.7)
			(stroke
				(width 0.2)
				(type solid)
			)
			(layer "B.SilkS")
		)
		(fp_line
			(start 0.65607 -0.7)
			(end -0.65607 -0.7)
			(stroke
				(width 0.2)
				(type solid)
			)
			(layer "B.SilkS")
		)
		(fp_line
			(start 0.75607 0.4)
			(end -0.75607 0.4)
			(stroke
				(width 0.2)
				(type solid)
			)
			(layer "B.CrtYd")
		)
		(fp_line
			(start 0.75607 -0.4)
			(end 0.75607 0.4)
			(stroke
				(width 0.2)
				(type solid)
			)
			(layer "B.CrtYd")
		)
		(fp_line
			(start 0.75607 -0.4)
			(end -0.75607 -0.4)
			(stroke
				(width 0.2)
				(type solid)
			)
			(layer "B.CrtYd")
		)
		(fp_line
			(start -0.75607 -0.4)
			(end -0.75607 0.4)
			(stroke
				(width 0.2)
				(type solid)
			)
			(layer "B.CrtYd")
		)
		(fp_line
			(start 0.75607 0.4)
			(end -0.75607 0.4)
			(stroke
				(width 0.2)
				(type solid)
			)
			(layer "B.Fab")
		)
		(fp_line
			(start 0.75607 -0.4)
			(end 0.75607 0.4)
			(stroke
				(width 0.2)
				(type solid)
			)
			(layer "B.Fab")
		)
		(fp_line
			(start 0.75607 -0.4)
			(end -0.75607 -0.4)
			(stroke
				(width 0.2)
				(type solid)
			)
			(layer "B.Fab")
		)
		(fp_line
			(start 0.5 0)
			(end -0.5 0)
			(stroke
				(width 0.1)
				(type solid)
			)
			(layer "B.Fab")
		)
		(fp_line
			(start 0 -0.5)
			(end 0 0.5)
			(stroke
				(width 0.1)
				(type solid)
			)
			(layer "B.Fab")
		)
		(fp_line
			(start -0.75607 -0.4)
			(end -0.75607 0.4)
			(stroke
				(width 0.2)
				(type solid)
			)
			(layer "B.Fab")
		)
		(fp_text user "${REFERENCE}"
			(at -0.00001 -0.09602 360)
			(unlocked yes)
			(layer "B.Fab")
			(effects
				(font
					(face "Arial")
					(size 0.63 0.63)
					(thickness 0.1)
				)
				(justify left bottom mirror)
			)
		)
		(pad "1" smd rect
			(at -0.36554 0 180)
			(size 0.58106 0.51213)
			(layers "B.Cu" "B.Mask" "B.Paste")
			(net "+3.3V")
			(solder_mask_margin 0)
			(solder_paste_margin 0)
		)
		(pad "2" smd rect
			(at 0.36554 0 180)
			(size 0.58106 0.51213)
			(layers "B.Cu" "B.Mask" "B.Paste")
			(net "GND")
			(solder_mask_margin 0)
			(solder_paste_margin 0)
		)
	)
	(footprint "Vault:FP-0402-L_1_0_1-W_0_5_0_1-IPC_C"
		(layer "B.Cu")
		(at 158.3216 129.5162 180)
		(property "Reference" "C94"
			(at 0.2286 1.687989 0)
			(unlocked yes)
			(layer "B.SilkS")
			(effects
				(font
					(size 0.762 0.762)
					(thickness 0.2286)
				)
				(justify mirror)
			)
		)
		(property "Value" "0.1uF_25V_0402"
			(at -2.465551 -9.839215 90)
			(unlocked yes)
			(layer "B.SilkS")
			(hide yes)
			(effects
				(font
					(size 0.762 0.762)
					(thickness 0.2286)
				)
				(justify mirror)
			)
		)
		(sheetname "09-USBUart_PPSMUX_UARTMUX")
		(sheetfile "09-USBUart_PPSMUX_UARTMUX.kicad_sch")
		(duplicate_pad_numbers_are_jumpers no)
		(fp_line
			(start 0.65607 0.7)
			(end -0.65607 0.7)
			(stroke
				(width 0.2)
				(type solid)
			)
			(layer "B.SilkS")
		)
		(fp_line
			(start 0.65607 -0.7)
			(end -0.65607 -0.7)
			(stroke
				(width 0.2)
				(type solid)
			)
			(layer "B.SilkS")
		)
		(fp_line
			(start 0.75607 0.4)
			(end -0.75607 0.4)
			(stroke
				(width 0.2)
				(type solid)
			)
			(layer "B.CrtYd")
		)
		(fp_line
			(start 0.75607 -0.4)
			(end 0.75607 0.4)
			(stroke
				(width 0.2)
				(type solid)
			)
			(layer "B.CrtYd")
		)
		(fp_line
			(start 0.75607 -0.4)
			(end -0.75607 -0.4)
			(stroke
				(width 0.2)
				(type solid)
			)
			(layer "B.CrtYd")
		)
		(fp_line
			(start -0.75607 -0.4)
			(end -0.75607 0.4)
			(stroke
				(width 0.2)
				(type solid)
			)
			(layer "B.CrtYd")
		)
		(fp_line
			(start 0.75607 0.4)
			(end -0.75607 0.4)
			(stroke
				(width 0.2)
				(type solid)
			)
			(layer "B.Fab")
		)
		(fp_line
			(start 0.75607 -0.4)
			(end 0.75607 0.4)
			(stroke
				(width 0.2)
				(type solid)
			)
			(layer "B.Fab")
		)
		(fp_line
			(start 0.75607 -0.4)
			(end -0.75607 -0.4)
			(stroke
				(width 0.2)
				(type solid)
			)
			(layer "B.Fab")
		)
		(fp_line
			(start 0.5 0)
			(end -0.5 0)
			(stroke
				(width 0.1)
				(type solid)
			)
			(layer "B.Fab")
		)
		(fp_line
			(start 0 -0.5)
			(end 0 0.5)
			(stroke
				(width 0.1)
				(type solid)
			)
			(layer "B.Fab")
		)
		(fp_line
			(start -0.75607 -0.4)
			(end -0.75607 0.4)
			(stroke
				(width 0.2)
				(type solid)
			)
			(layer "B.Fab")
		)
		(fp_text user "${REFERENCE}"
			(at -0.00001 -0.09602 360)
			(unlocked yes)
			(layer "B.Fab")
			(effects
				(font
					(face "Arial")
					(size 0.63 0.63)
					(thickness 0.1)
				)
				(justify left bottom mirror)
			)
		)
		(pad "1" smd rect
			(at -0.36554 0 180)
			(size 0.58106 0.51213)
			(layers "B.Cu" "B.Mask" "B.Paste")
			(net "+3.3V")
			(solder_mask_margin 0)
			(solder_paste_margin 0)
		)
		(pad "2" smd rect
			(at 0.36554 0 180)
			(size 0.58106 0.51213)
			(layers "B.Cu" "B.Mask" "B.Paste")
			(net "GND")
			(solder_mask_margin 0)
			(solder_paste_margin 0)
		)
	)
	(footprint "Vault:RESC1005X40X25NL10T10"
		(layer "B.Cu")
		(at 76.7216 129.9162 90)
		(property "Reference" "R16"
			(at 2.0714 0.026931 90)
			(unlocked yes)
			(layer "B.SilkS")
			(effects
				(font
					(size 0.762 0.762)
					(thickness 0.2286)
				)
				(justify mirror)
			)
		)
		(property "Value" "4.7K_1%_0402"
			(at -0.558471 -4.825345 0)
			(unlocked yes)
			(layer "B.SilkS")
			(hide yes)
			(effects
				(font
					(size 0.762 0.762)
					(thickness 0.2286)
				)
				(justify mirror)
			)
		)
		(sheetname "01-USER_IO")
		(sheetfile "01-USER_IO.kicad_sch")
		(duplicate_pad_numbers_are_jumpers no)
		(pad "1" smd rect
			(at -0.425 0)
			(size 0.6 0.65)
			(layers "B.Cu" "B.Mask" "B.Paste")
			(net "+3.3V")
		)
		(pad "2" smd rect
			(at 0.425 0)
			(size 0.6 0.65)
			(layers "B.Cu" "B.Mask" "B.Paste")
			(net "ANT3_IO_IN")
		)
	)
	(footprint "Vault:RESC1005X40X25NL05T05"
		(layer "B.Cu")
		(at 220.6216 113.7162 -90)
		(property "Reference" "R122"
			(at -0.0968 1.273079 90)
			(unlocked yes)
			(layer "B.SilkS")
			(effects
				(font
					(size 0.762 0.762)
					(thickness 0.2032)
				)
				(justify mirror)
			)
		)
		(property "Value" "200_1%_0402"
			(at -2.732271 -8.112675 180)
			(unlocked yes)
			(layer "B.SilkS")
			(hide yes)
			(effects
				(font
					(size 0.762 0.762)
					(thickness 0.2032)
				)
				(justify mirror)
			)
		)
		(sheetname "08-DIPSwitches_I2C")
		(sheetfile "08-DIPSwitches_I2C.kicad_sch")
		(duplicate_pad_numbers_are_jumpers no)
		(pad "1" smd rect
			(at -0.45 0 180)
			(size 0.55 0.55)
			(layers "B.Cu" "B.Mask" "B.Paste")
			(net "NetD22_1")
		)
		(pad "2" smd rect
			(at 0.45 0 180)
			(size 0.55 0.55)
			(layers "B.Cu" "B.Mask" "B.Paste")
			(net "DIP_SW_PPS_SEL")
		)
	)
	(footprint "Vault:CAPC1608X87X45ML20T05"
		(layer "B.Cu")
		(at 180.30985 105.2162 -90)
		(property "Reference" "C25"
			(at -2.4338 0.023079 90)
			(unlocked yes)
			(layer "B.SilkS")
			(effects
				(font
					(size 0.762 0.762)
					(thickness 0.2286)
				)
				(justify mirror)
			)
		)
		(property "Value" "0.1uF"
			(at 2.069025 -2.630671 90)
			(unlocked yes)
			(layer "B.SilkS")
			(hide yes)
			(effects
				(font
					(size 0.762 0.762)
					(thickness 0.2286)
				)
				(justify mirror)
			)
		)
		(sheetname "05-GPS_IMU_SENSORS")
		(sheetfile "05-GPS_IMU_SENSORS.kicad_sch")
		(duplicate_pad_numbers_are_jumpers no)
		(pad "1" smd rect
			(at -0.7 0 180)
			(size 1.1 1.05)
			(layers "B.Cu" "B.Mask" "B.Paste")
			(net "GND")
		)
		(pad "2" smd rect
			(at 0.7 0 180)
			(size 1.1 1.05)
			(layers "B.Cu" "B.Mask" "B.Paste")
			(net "+3.3V")
		)
	)
	(footprint "Vault:RESC1005X40X25LL05T05"
		(layer "B.Cu")
		(at 112.58072 86.8662)
		(property "Reference" "R55"
			(at -0.23052 6.823069 180)
			(unlocked yes)
			(layer "B.SilkS")
			(effects
				(font
					(size 0.762 0.762)
					(thickness 0.2286)
				)
				(justify mirror)
			)
		)
		(property "Value" "4.7K_0402"
			(at -3.024391 -2.374045 270)
			(unlocked yes)
			(layer "B.SilkS")
			(hide yes)
			(effects
				(font
					(size 0.762 0.762)
					(thickness 0.2286)
				)
				(justify mirror)
			)
		)
		(sheetname "05-GPS_IMU_SENSORS")
		(sheetfile "05-GPS_IMU_SENSORS.kicad_sch")
		(duplicate_pad_numbers_are_jumpers no)
		(pad "1" smd rect
			(at -0.4 0 270)
			(size 0.45 0.45)
			(layers "B.Cu" "B.Mask" "B.Paste")
			(net "BNO_BLIND")
		)
		(pad "2" smd rect
			(at 0.40001 0 270)
			(size 0.45 0.45)
			(layers "B.Cu" "B.Mask" "B.Paste")
			(net "NetR55_2")
		)
	)
	(footprint "Vault:RESC1005X40X25NL10T10"
		(layer "B.Cu")
		(at 88.1716 56.5662)
		(property "Reference" "R9"
			(at 0.75 -0.456655 0)
			(unlocked yes)
			(layer "B.SilkS")
			(effects
				(font
					(size 0.762 0.762)
					(thickness 0.2286)
				)
				(justify left bottom mirror)
			)
		)
		(property "Value" "20K_1%_0402"
			(at -10.4651 10.660245 0)
			(unlocked yes)
			(layer "B.SilkS")
			(hide yes)
			(effects
				(font
					(size 0.762 0.762)
					(thickness 0.2286)
				)
				(justify left bottom mirror)
			)
		)
		(sheetname "03-POWER")
		(sheetfile "03-POWER.kicad_sch")
		(duplicate_pad_numbers_are_jumpers no)
		(pad "1" smd rect
			(at -0.425 0 270)
			(size 0.6 0.65)
			(layers "B.Cu" "B.Mask" "B.Paste")
			(net "+12V")
		)
		(pad "2" smd rect
			(at 0.425 0 270)
			(size 0.6 0.65)
			(layers "B.Cu" "B.Mask" "B.Paste")
			(net "NetR9_2")
		)
	)
	(footprint "Vault:CAPC1608X87X45ML20T05"
		(layer "B.Cu")
		(at 207.6216 131.5162 180)
		(property "Reference" "C36"
			(at 0.1286 1.373079 0)
			(unlocked yes)
			(layer "B.SilkS")
			(effects
				(font
					(size 0.762 0.762)
					(thickness 0.2286)
				)
				(justify mirror)
			)
		)
		(property "Value" "0.1uF"
			(at 2.069035 -2.630671 0)
			(unlocked yes)
			(layer "B.SilkS")
			(hide yes)
			(effects
				(font
					(size 0.762 0.762)
					(thickness 0.2286)
				)
				(justify mirror)
			)
		)
		(sheetname "05-GPS_IMU_SENSORS")
		(sheetfile "05-GPS_IMU_SENSORS.kicad_sch")
		(duplicate_pad_numbers_are_jumpers no)
		(pad "1" smd rect
			(at -0.7 0 90)
			(size 1.1 1.05)
			(layers "B.Cu" "B.Mask" "B.Paste")
			(net "GND")
		)
		(pad "2" smd rect
			(at 0.7 0 90)
			(size 1.1 1.05)
			(layers "B.Cu" "B.Mask" "B.Paste")
			(net "GNSS2_P3V3")
		)
	)
	(footprint "Vault:FP-0402-L_1_0_1-W_0_5_0_1-IPC_C"
		(layer "B.Cu")
		(at 126.5216 74.1162 -90)
		(property "Reference" "C100"
			(at 2.8887 -0.141431 90)
			(unlocked yes)
			(layer "B.SilkS")
			(effects
				(font
					(size 0.762 0.762)
					(thickness 0.2032)
				)
				(justify mirror)
			)
		)
		(property "Value" "0.1uF_25V_0402"
			(at -2.465551 -9.813805 180)
			(unlocked yes)
			(layer "B.SilkS")
			(hide yes)
			(effects
				(font
					(size 0.762 0.762)
					(thickness 0.2032)
				)
				(justify mirror)
			)
		)
		(sheetname "10-M2_GPS")
		(sheetfile "10-M2_GPS.kicad_sch")
		(duplicate_pad_numbers_are_jumpers no)
		(fp_line
			(start 0.65607 0.7)
			(end -0.65607 0.7)
			(stroke
				(width 0.2)
				(type solid)
			)
			(layer "B.SilkS")
		)
		(fp_line
			(start 0.65607 -0.7)
			(end -0.65607 -0.7)
			(stroke
				(width 0.2)
				(type solid)
			)
			(layer "B.SilkS")
		)
		(fp_line
			(start -0.75607 0.4)
			(end -0.75607 -0.4)
			(stroke
				(width 0.2)
				(type solid)
			)
			(layer "B.CrtYd")
		)
		(fp_line
			(start 0.75607 0.4)
			(end -0.75607 0.4)
			(stroke
				(width 0.2)
				(type solid)
			)
			(layer "B.CrtYd")
		)
		(fp_line
			(start 0.75607 0.4)
			(end 0.75607 -0.4)
			(stroke
				(width 0.2)
				(type solid)
			)
			(layer "B.CrtYd")
		)
		(fp_line
			(start 0.75607 -0.4)
			(end -0.75607 -0.4)
			(stroke
				(width 0.2)
				(type solid)
			)
			(layer "B.CrtYd")
		)
		(fp_line
			(start 0 0.5)
			(end 0 -0.5)
			(stroke
				(width 0.1)
				(type solid)
			)
			(layer "B.Fab")
		)
		(fp_line
			(start -0.75607 0.4)
			(end -0.75607 -0.4)
			(stroke
				(width 0.2)
				(type solid)
			)
			(layer "B.Fab")
		)
		(fp_line
			(start 0.75607 0.4)
			(end -0.75607 0.4)
			(stroke
				(width 0.2)
				(type solid)
			)
			(layer "B.Fab")
		)
		(fp_line
			(start 0.75607 0.4)
			(end 0.75607 -0.4)
			(stroke
				(width 0.2)
				(type solid)
			)
			(layer "B.Fab")
		)
		(fp_line
			(start 0.5 0)
			(end -0.5 0)
			(stroke
				(width 0.1)
				(type solid)
			)
			(layer "B.Fab")
		)
		(fp_line
			(start 0.75607 -0.4)
			(end -0.75607 -0.4)
			(stroke
				(width 0.2)
				(type solid)
			)
			(layer "B.Fab")
		)
		(fp_text user "${REFERENCE}"
			(at -0.00001 -0.09602 90)
			(unlocked yes)
			(layer "B.Fab")
			(effects
				(font
					(face "Arial")
					(size 0.63 0.63)
					(thickness 0.1)
				)
				(justify left bottom mirror)
			)
		)
		(pad "1" smd rect
			(at -0.36554 0 270)
			(size 0.58106 0.51213)
			(layers "B.Cu" "B.Mask" "B.Paste")
			(net "+3.3V")
			(solder_mask_margin 0)
			(solder_paste_margin 0)
		)
		(pad "2" smd rect
			(at 0.36554 0 270)
			(size 0.58106 0.51213)
			(layers "B.Cu" "B.Mask" "B.Paste")
			(net "GND")
			(solder_mask_margin 0)
			(solder_paste_margin 0)
		)
	)
	(footprint "Vault:FP-MK212BG-MFG"
		(layer "B.Cu")
		(at 207.5592 138.64087)
		(property "Reference" "C35"
			(at -0.28601 -1.566639 0)
			(unlocked yes)
			(layer "B.SilkS")
			(effects
				(font
					(size 0.762 0.762)
					(thickness 0.2286)
				)
				(justify mirror)
			)
		)
		(property "Value" "10uF"
			(at -3.240271 -2.22164 270)
			(unlocked yes)
			(layer "B.SilkS")
			(hide yes)
			(effects
				(font
					(size 0.762 0.762)
					(thickness 0.2286)
				)
				(justify mirror)
			)
		)
		(sheetname "05-GPS_IMU_SENSORS")
		(sheetfile "05-GPS_IMU_SENSORS.kicad_sch")
		(duplicate_pad_numbers_are_jumpers no)
		(fp_line
			(start -0.125 -0.725)
			(end 0.125 -0.725)
			(stroke
				(width 0.2)
				(type solid)
			)
			(layer "B.SilkS")
		)
		(fp_line
			(start -0.125 0.725)
			(end 0.125 0.725)
			(stroke
				(width 0.2)
				(type solid)
			)
			(layer "B.SilkS")
		)
		(fp_line
			(start -1.6 -0.825)
			(end 1.6 -0.825)
			(stroke
				(width 0.2)
				(type solid)
			)
			(layer "B.CrtYd")
		)
		(fp_line
			(start -1.6 0.825)
			(end -1.6 -0.825)
			(stroke
				(width 0.2)
				(type solid)
			)
			(layer "B.CrtYd")
		)
		(fp_line
			(start -1.6 0.825)
			(end 1.6 0.825)
			(stroke
				(width 0.2)
				(type solid)
			)
			(layer "B.CrtYd")
		)
		(fp_line
			(start 1.6 0.825)
			(end 1.6 -0.825)
			(stroke
				(width 0.2)
				(type solid)
			)
			(layer "B.CrtYd")
		)
		(fp_line
			(start -1.6 -0.825)
			(end 1.6 -0.825)
			(stroke
				(width 0.2)
				(type solid)
			)
			(layer "B.Fab")
		)
		(fp_line
			(start -1.6 0.825)
			(end -1.6 -0.825)
			(stroke
				(width 0.2)
				(type solid)
			)
			(layer "B.Fab")
		)
		(fp_line
			(start -1.6 0.825)
			(end 1.6 0.825)
			(stroke
				(width 0.2)
				(type solid)
			)
			(layer "B.Fab")
		)
		(fp_line
			(start -0.5 0)
			(end 0.5 0)
			(stroke
				(width 0.1)
				(type solid)
			)
			(layer "B.Fab")
		)
		(fp_line
			(start 0 0.5)
			(end 0 -0.5)
			(stroke
				(width 0.1)
				(type solid)
			)
			(layer "B.Fab")
		)
		(fp_line
			(start 1.6 0.825)
			(end 1.6 -0.825)
			(stroke
				(width 0.2)
				(type solid)
			)
			(layer "B.Fab")
		)
		(fp_text user "${REFERENCE}"
			(at -0.00001 -0.09601 180)
			(unlocked yes)
			(layer "B.Fab")
			(effects
				(font
					(face "Arial")
					(size 0.63 0.63)
					(thickness 0.1)
				)
				(justify left bottom mirror)
			)
		)
		(pad "1" smd rect
			(at -1 0)
			(size 1 1.25)
			(layers "B.Cu" "B.Mask" "B.Paste")
			(net "GNSS2_P5V0")
			(solder_mask_margin 0)
			(solder_paste_margin 0)
		)
		(pad "2" smd rect
			(at 1 0)
			(size 1 1.25)
			(layers "B.Cu" "B.Mask" "B.Paste")
			(net "GND")
			(solder_mask_margin 0)
			(solder_paste_margin 0)
		)
	)
	(footprint "Vault:RESC1005X40X25NL10T10"
		(layer "B.Cu")
		(at 74.3216 103.7162 90)
		(property "Reference" "R15"
			(at 2.7714 0.026931 90)
			(unlocked yes)
			(layer "B.SilkS")
			(effects
				(font
					(size 0.762 0.762)
					(thickness 0.2286)
				)
				(justify mirror)
			)
		)
		(property "Value" "4.7K_1%_0402"
			(at -3.433471 -5.789055 0)
			(unlocked yes)
			(layer "B.SilkS")
			(hide yes)
			(effects
				(font
					(size 0.762 0.762)
					(thickness 0.2286)
				)
				(justify mirror)
			)
		)
		(sheetname "01-USER_IO")
		(sheetfile "01-USER_IO.kicad_sch")
		(duplicate_pad_numbers_are_jumpers no)
		(pad "1" smd rect
			(at -0.425 0)
			(size 0.6 0.65)
			(layers "B.Cu" "B.Mask" "B.Paste")
			(net "+3.3V")
		)
		(pad "2" smd rect
			(at 0.425 0)
			(size 0.6 0.65)
			(layers "B.Cu" "B.Mask" "B.Paste")
			(net "ANT1_IO_IN")
		)
	)
)
